# T6G (Grand Teton) — schematic netlist excerpt (pin names and nets, part order shuffled) for the footprints in the layout excerpt that follows; sources: Cadence DE-HDL packaged netlist, KiCad conversion of 04192023_DAF0TMB3IC0_F0TG_MB_C_brd_V02_OCP.brd

X8001  TP_TDR_4P_FTS  TP_TDR_4P_DIP EMPTY  pkg TH  page 260
  S1  = TDR_DIFF_85_TOP_DP
  P1  = T1_GND
  P2  = T1_GND
  S2  = TDR_DIFF_85_TOP_DN

C2017  Q_CAP  0.1UF 25V 10% X7R  pkg 0402  page 237 : A = P3V3_OCP_V3_2_R ; B = GND

(kicad_pcb
	(version 20260206)
	(generator "pcbnew")
	(generator_version "10.0")
	(general
		(thickness 1.6)
		(legacy_teardrops no)
	)
	(paper "A4")
	(title_block
		(title "04192023_DAF0TMB3IC0_F0TG_MB_C_brd_V02_OCP.brd")
		(comment 1 "Grand Teton / footprints 12-13 of 8354")
	)
	(layers
		(0 "F.Cu" signal "TOP")
		(4 "In1.Cu" signal "GND")
		(6 "In2.Cu" signal "IN1")
		(8 "In3.Cu" signal "GND1")
		(10 "In4.Cu" signal "IN2")
		(12 "In5.Cu" signal "GND2")
		(14 "In6.Cu" signal "IN3")
		(16 "In7.Cu" signal "GND3")
		(18 "In8.Cu" signal "VCC")
		(20 "In9.Cu" signal "VCC1")
		(22 "In10.Cu" signal "GND4")
		(24 "In11.Cu" signal "IN4")
		(26 "In12.Cu" signal "GND5")
		(28 "In13.Cu" signal "IN5")
		(30 "In14.Cu" signal "GND6")
		(32 "In15.Cu" signal "IN6")
		(34 "In16.Cu" signal "GND7")
		(2 "B.Cu" signal "BOTTOM")
		(9 "F.Adhes" user "F.Adhesive")
		(11 "B.Adhes" user "B.Adhesive")
		(13 "F.Paste" user "Package Geometry/Pastemask Top")
		(15 "B.Paste" user "Package Geometry/Pastemask Bottom")
		(5 "F.SilkS" user "Ref Des/Silkscreen Top")
		(7 "B.SilkS" user "Ref Des/Silkscreen Bottom")
		(1 "F.Mask" user "Board Geometry/Soldermask Top")
		(3 "B.Mask" user "Board Geometry/Soldermask Bottom")
		(17 "Dwgs.User" user "User.Drawings")
		(19 "Cmts.User" user "User.Comments")
		(21 "Eco1.User" user "User.Eco1")
		(23 "Eco2.User" user "User.Eco2")
		(25 "Edge.Cuts" user "Board Geometry/Outline")
		(27 "Margin" user)
		(31 "F.CrtYd" user "Package Geometry/Place Bound Top")
		(29 "B.CrtYd" user "Package Geometry/Place Bound Bottom")
		(35 "F.Fab" user "Ref Des/Assembly Top")
		(33 "B.Fab" user "Ref Des/Assembly Bottom")
	)
	(footprint ""
		(layer "F.Cu")
		(at 522.584426 7.535926 -90)
		(property "Reference" "X8001"
			(at -1.918208 5.481574 0)
			(unlocked yes)
			(layer "F.SilkS")
			(effects
				(font
					(size 0.7874 0.5842)
					(thickness 0.1524)
				)
				(justify left)
			)
		)
		(property "Value" ""
			(at 0 0 270)
			(layer "F.Fab")
			(effects
				(font
					(size 1.27 1.27)
				)
			)
		)
		(property "Device Type" "TP_TDR_4P_FTS_TH-TP_TDR_4P_DIP,EMPTY,TP15"
			(at 1.30175 1.27 0)
			(unlocked yes)
			(layer "F.Fab")
			(hide yes)
			(effects
				(font
					(size 0.635 0.4064)
					(thickness 0.1524)
				)
			)
		)
		(property "User Part Number" "N_A"
			(at 1.30175 1.27 0)
			(unlocked yes)
			(layer "Cmts.User")
			(hide yes)
			(effects
				(font
					(size 0.635 0.4064)
					(thickness 0.1524)
				)
			)
		)
		(duplicate_pad_numbers_are_jumpers no)
		(fp_line
			(start 0 3.81)
			(end 2.54 3.81)
			(stroke
				(width 0.1524)
				(type default)
			)
			(layer "F.SilkS")
		)
		(fp_line
			(start 2.54 3.81)
			(end 2.54 3.6703)
			(stroke
				(width 0.1524)
				(type default)
			)
			(layer "F.SilkS")
		)
		(fp_line
			(start 0 3.175)
			(end 0 3.81)
			(stroke
				(width 0.1524)
				(type default)
			)
			(layer "F.SilkS")
		)
		(fp_line
			(start 2.54 1.4097)
			(end 2.54 1.1303)
			(stroke
				(width 0.1524)
				(type default)
			)
			(layer "F.SilkS")
		)
		(fp_line
			(start 0 0.635)
			(end 0 1.905)
			(stroke
				(width 0.1524)
				(type default)
			)
			(layer "F.SilkS")
		)
		(fp_line
			(start 2.54 -1.1303)
			(end 2.54 -1.27)
			(stroke
				(width 0.1524)
				(type default)
			)
			(layer "F.SilkS")
		)
		(fp_line
			(start 0 -1.27)
			(end 0 -0.635)
			(stroke
				(width 0.1524)
				(type default)
			)
			(layer "F.SilkS")
		)
		(fp_line
			(start 2.54 -1.27)
			(end 0 -1.27)
			(stroke
				(width 0.1524)
				(type default)
			)
			(layer "F.SilkS")
		)
		(fp_poly
			(pts
				(xy -2.285746 -0.762) (xy -0.761746 0) (xy -2.285746 0.762)
			)
			(stroke
				(width 0)
				(type default)
			)
			(fill yes)
			(layer "F.SilkS")
		)
		(fp_line
			(start 0 3.81)
			(end 2.54 3.81)
			(stroke
				(width 0.1)
				(type default)
			)
			(layer "F.Fab")
		)
		(fp_line
			(start 2.54 3.81)
			(end 2.54 -1.27)
			(stroke
				(width 0.1)
				(type default)
			)
			(layer "F.Fab")
		)
		(fp_line
			(start 0 -1.27)
			(end 0 3.81)
			(stroke
				(width 0.1)
				(type default)
			)
			(layer "F.Fab")
		)
		(fp_line
			(start 2.54 -1.27)
			(end 0 -1.27)
			(stroke
				(width 0.1)
				(type default)
			)
			(layer "F.Fab")
		)
		(fp_poly
			(pts
				(xy -0.761746 0) (xy -2.285746 -0.762) (xy -2.285746 0.762)
			)
			(stroke
				(width 0)
				(type default)
			)
			(fill yes)
			(layer "F.Fab")
		)
		(pad "1" thru_hole circle
			(at 0 0 270)
			(size 1.0033 1.0033)
			(drill 0.249936)
			(layers "*.Cu" "*.Mask")
			(remove_unused_layers no)
			(net "TDR_DIFF_85_TOP_DP")
			(clearance 0.10795)
			(thermal_gap 0.10795)
			(padstack
				(mode front_inner_back)
				(layer "Inner"
					(shape circle)
					(size 0.8001 0.8001)
					(clearance 0.1524)
				)
				(layer "B.Cu"
					(shape circle)
					(size 1.0033 1.0033)
					(clearance 0.10795)
				)
			)
		)
		(pad "2" thru_hole circle
			(at 2.54 0 270)
			(size 1.9939 1.9939)
			(drill 0.249936)
			(layers "*.Cu" "*.Mask")
			(remove_unused_layers no)
			(net "T1_GND")
			(clearance 0.10795)
			(thermal_gap 0.10795)
			(padstack
				(mode front_inner_back)
				(layer "Inner"
					(shape circle)
					(size 0.8001 0.8001)
					(clearance 0.1524)
				)
				(layer "B.Cu"
					(shape circle)
					(size 1.9939 1.9939)
					(clearance 0.10795)
				)
			)
		)
		(pad "3" thru_hole circle
			(at 2.54 2.54 270)
			(size 1.9939 1.9939)
			(drill 0.249936)
			(layers "*.Cu" "*.Mask")
			(remove_unused_layers no)
			(net "T1_GND")
			(clearance 0.10795)
			(thermal_gap 0.10795)
			(padstack
				(mode front_inner_back)
				(layer "Inner"
					(shape circle)
					(size 0.8001 0.8001)
					(clearance 0.1524)
				)
				(layer "B.Cu"
					(shape circle)
					(size 1.9939 1.9939)
					(clearance 0.10795)
				)
			)
		)
		(pad "4" thru_hole circle
			(at 0 2.54 270)
			(size 1.0033 1.0033)
			(drill 0.249936)
			(layers "*.Cu" "*.Mask")
			(remove_unused_layers no)
			(net "TDR_DIFF_85_TOP_DN")
			(clearance 0.10795)
			(thermal_gap 0.10795)
			(padstack
				(mode front_inner_back)
				(layer "Inner"
					(shape circle)
					(size 0.8001 0.8001)
					(clearance 0.1524)
				)
				(layer "B.Cu"
					(shape circle)
					(size 1.0033 1.0033)
					(clearance 0.10795)
				)
			)
		)
	)
	(footprint ""
		(layer "F.Cu")
		(at 75.705462 -39.675562)
		(property "Reference" "C2017"
			(at 0 0 0)
			(layer "F.SilkS")
			(hide yes)
			(effects
				(font
					(size 1.27 1.27)
				)
			)
		)
		(property "Value" ""
			(at 0 0 0)
			(layer "F.Fab")
			(effects
				(font
					(size 1.27 1.27)
				)
			)
		)
		(duplicate_pad_numbers_are_jumpers no)
		(fp_line
			(start -0.7874 -0.4064)
			(end 0.7874 -0.4064)
			(stroke
				(width 0.1524)
				(type default)
			)
			(layer "F.SilkS")
		)
		(fp_line
			(start -0.7874 0.4064)
			(end -0.7874 -0.4064)
			(stroke
				(width 0.1524)
				(type default)
			)
			(layer "F.SilkS")
		)
		(fp_line
			(start 0.7874 -0.4064)
			(end 0.7874 0.4064)
			(stroke
				(width 0.1524)
				(type default)
			)
			(layer "F.SilkS")
		)
		(fp_line
			(start 0.7874 0.4064)
			(end -0.7874 0.4064)
			(stroke
				(width 0.1524)
				(type default)
			)
			(layer "F.SilkS")
		)
		(fp_line
			(start -0.67945 -0.305054)
			(end -0.12065 -0.305054)
			(stroke
				(width 0.1)
				(type default)
			)
			(layer "F.Fab")
		)
		(fp_line
			(start -0.67945 0.3048)
			(end -0.67945 -0.305054)
			(stroke
				(width 0.1)
				(type default)
			)
			(layer "F.Fab")
		)
		(fp_line
			(start -0.12065 -0.305054)
			(end -0.12065 -0.2794)
			(stroke
				(width 0.1)
				(type default)
			)
			(layer "F.Fab")
		)
		(fp_line
			(start -0.12065 -0.2794)
			(end 0.12065 -0.2794)
			(stroke
				(width 0.1)
				(type default)
			)
			(layer "F.Fab")
		)
		(fp_line
			(start -0.12065 0.2794)
			(end -0.12065 0.3048)
			(stroke
				(width 0.1)
				(type default)
			)
			(layer "F.Fab")
		)
		(fp_line
			(start -0.12065 0.3048)
			(end -0.67945 0.3048)
			(stroke
				(width 0.1)
				(type default)
			)
			(layer "F.Fab")
		)
		(fp_line
			(start 0.120396 0.2794)
			(end -0.12065 0.2794)
			(stroke
				(width 0.1)
				(type default)
			)
			(layer "F.Fab")
		)
		(fp_line
			(start 0.120396 0.3048)
			(end 0.120396 0.2794)
			(stroke
				(width 0.1)
				(type default)
			)
			(layer "F.Fab")
		)
		(fp_line
			(start 0.12065 -0.3048)
			(end 0.67945 -0.3048)
			(stroke
				(width 0.1)
				(type default)
			)
			(layer "F.Fab")
		)
		(fp_line
			(start 0.12065 -0.2794)
			(end 0.12065 -0.3048)
			(stroke
				(width 0.1)
				(type default)
			)
			(layer "F.Fab")
		)
		(fp_line
			(start 0.67945 -0.3048)
			(end 0.67945 0.3048)
			(stroke
				(width 0.1)
				(type default)
			)
			(layer "F.Fab")
		)
		(fp_line
			(start 0.67945 0.3048)
			(end 0.120396 0.3048)
			(stroke
				(width 0.1)
				(type default)
			)
			(layer "F.Fab")
		)
		(pad "1" smd circle
			(at -0.40005 0)
			(size 0 0)
			(layers "F.Cu" "F.Mask" "F.Paste")
			(net "P3V3_OCP_V3_2_R")
		)
		(pad "2" smd circle
			(at 0.40005 0)
			(size 0 0)
			(layers "F.Cu" "F.Mask" "F.Paste")
			(net "GND")
		)
	)
)
